FILE_TYPE=LIBRARY_PARTS;
primitive 'CONN8_C77962004','CONN8_C77962004_CONNLF';
  pin
    'IO1':
      PIN_NUMBER='(1)';
	INPUT_LOAD='(-0.01,0.01)';
	OUTPUT_LOAD='(1.0,-1.0)';
	OUTPUT_TYPE='(TS,TS)';
	BIDIRECTIONAL='TRUE';
    'IO2':
      PIN_NUMBER='(2)';
	INPUT_LOAD='(-0.01,0.01)';
	OUTPUT_LOAD='(1.0,-1.0)';
	OUTPUT_TYPE='(TS,TS)';
	BIDIRECTIONAL='TRUE';
    'IO3':
      PIN_NUMBER='(3)';
	INPUT_LOAD='(-0.01,0.01)';
	OUTPUT_LOAD='(1.0,-1.0)';
	OUTPUT_TYPE='(TS,TS)';
	BIDIRECTIONAL='TRUE';
    'IO4':
      PIN_NUMBER='(4)';
	INPUT_LOAD='(-0.01,0.01)';
	OUTPUT_LOAD='(1.0,-1.0)';
	OUTPUT_TYPE='(TS,TS)';
	BIDIRECTIONAL='TRUE';
    'IO5':
      PIN_NUMBER='(5)';
	INPUT_LOAD='(-0.01,0.01)';
	OUTPUT_LOAD='(1.0,-1.0)';
	OUTPUT_TYPE='(TS,TS)';
	BIDIRECTIONAL='TRUE';
    'IO6':
      PIN_NUMBER='(6)';
	INPUT_LOAD='(-0.01,0.01)';
	OUTPUT_LOAD='(1.0,-1.0)';
	OUTPUT_TYPE='(TS,TS)';
	BIDIRECTIONAL='TRUE';
    'IO7':
      PIN_NUMBER='(7)';
	INPUT_LOAD='(-0.01,0.01)';
	OUTPUT_LOAD='(1.0,-1.0)';
	OUTPUT_TYPE='(TS,TS)';
	BIDIRECTIONAL='TRUE';
    'IO8':
      PIN_NUMBER='(8)';
	INPUT_LOAD='(-0.01,0.01)';
	OUTPUT_LOAD='(1.0,-1.0)';
	OUTPUT_TYPE='(TS,TS)';
	BIDIRECTIONAL='TRUE';
  end_pin;
  body
    PART_NAME='CONN8_C77962004';
    CLASS ='IO';
    PHYS_DES_PREFIX='J';
   end_body;
end_primitive;
END.
